#ISCELL
  mstr_misc dns *
  *
#ISCELL
  mstr_symbols cad_note *
  *
#ISCELL
  mstr_symbols intel_corp_bpage *
  *
#CELL
  mstr_discrete choke_4pin *
  page253_i11
#CELL
  mstr_discrete res *
  page253_i12
#CELL
  mstr_discrete res *
  page253_i13
#CELL
  mstr_discrete res *
  page253_i14
#CELL
  mstr_discrete res *
  page253_i15
#CELL
  mstr_discrete choke_4pin *
  page253_i16
#CELL
  dev_discrete cap_a *
  page253_i19
#CELL
  dev_discrete cap_a *
  page253_i20
#ISCELL
  mstr_standard offpage *
  page253_i22
#ISCELL
  mstr_standard offpage *
  page253_i23
#ISCELL
  mstr_standard offpage *
  page253_i24
#ISCELL
  mstr_standard offpage *
  page253_i25
#CELL
  w_hdl skt-usb32-8-gp *
  page253_i26
#ISCELL
  mstr_symbols gnd *
  page253_i27
#ISCELL
  mstr_symbols p5v_stby *
  page253_i29
#CELL
  w_hdl sc22u16v5mx-4-gp *
  page253_i35
#CELL
  w_hdl sc22u16v5mx-4-gp *
  page253_i36
#CELL
  w_hdl sc22u16v5mx-4-gp *
  page253_i37
#CELL
  w_hdl sc22u16v5mx-4-gp *
  page253_i38
#CELL
  w_hdl sc22u16v5mx-4-gp *
  page253_i40
#CELL
  w_hdl sc22u16v5mx-4-gp *
  page253_i41
#CELL
  w_hdl sc22u16v5mx-4-gp *
  page253_i42
#ISCELL
  mstr_symbols gnd *
  page253_i43
#CELL
  w_hdl polysw-1d1a6v-2-gp-u *
  page253_i44
#CELL
  mstr_discrete diodeac_dual_array *
  page253_i5
#ISCELL
  mstr_symbols gnd *
  page253_i9
